# BASEBOARD_FAB2 (Tioga Pass) — schematic netlist excerpt (pin names and nets, part order shuffled) for the footprints in the layout excerpt that follows; sources: Cadence DE-HDL packaged netlist, KiCad conversion of Wiwynn_Tioga_Pass_MB.brd

J1G3  SCONN288_H44441004  SCONN  pkg PIP  page 81
  \12v\(1)  = P12V_NVDIMM_GHJ
  VSS(93)  = GND
  DQ(4)  = M_J_DQ<5>
  VSS(92)  = GND
  DQ(0)  = M_J_DQ<1>
  VSS(91)  = GND
  DQS9P  = M_J_DQS_DP<9>
  DQS9N  = M_J_DQS_DN<9>
  VSS(90)  = GND
  DQ(6)  = M_J_DQ<7>
  VSS(89)  = GND
  DQ(2)  = M_J_DQ<3>
  VSS(88)  = GND
  DQ(12)  = M_J_DQ<13>
  VSS(87)  = GND
  DQ(8)  = M_J_DQ<9>
  VSS(86)  = GND
  DQS10P  = M_J_DQS_DP<10>
  DQS10N  = M_J_DQS_DN<10>
  VSS(85)  = GND
  DQ(14)  = M_J_DQ<15>
  VSS(84)  = GND
  DQ(10)  = M_J_DQ<11>
  VSS(83)  = GND
  DQ(20)  = M_J_DQ<21>
  VSS(82)  = GND
  DQ(16)  = M_J_DQ<17>
  VSS(81)  = GND
  DQS11P  = M_J_DQS_DP<11>
  DQS11N  = M_J_DQS_DN<11>
  VSS(80)  = GND
  DQ(22)  = M_J_DQ<23>
  VSS(79)  = GND
  DQ(18)  = M_J_DQ<19>
  VSS(78)  = GND
  DQ(28)  = M_J_DQ<29>
  VSS(77)  = GND
  DQ(24)  = M_J_DQ<25>
  VSS(76)  = GND
  DQS12P  = M_J_DQS_DP<12>
  DQS12N  = M_J_DQS_DN<12>
  VSS(75)  = GND
  DQ(30)  = M_J_DQ<31>
  VSS(74)  = GND
  DQ(26)  = M_J_DQ<27>
  VSS(73)  = GND
  CB(4)  = M_J_ECC<5>
  VSS(72)  = GND
  CB(0)  = M_J_ECC<1>
  VSS(71)  = GND
  DQS17P  = M_J_DQS_DP<17>
  DQS17N  = M_J_DQS_DN<17>
  VSS(70)  = GND
  CB(6)  = M_J_ECC<7>
  VSS(69)  = GND
  CB(2)  = M_J_ECC<3>
  VSS(68)  = GND
  RESET_N  = M_GHJ_RST_N
  VDD(25)  = PVDDQ_GHJ
  CKE(0)  = M_J_CKE<0>
  VDD(24)  = PVDDQ_GHJ
  ACT_N  = M_J_ACT_N
  BG(0)  = M_J_BG<0>
  VDD(23)  = PVDDQ_GHJ
  A12  = M_J_MA<12>
  A9  = M_J_MA<9>
  VDD(22)  = PVDDQ_GHJ
  A8  = M_J_MA<8>
  A6  = M_J_MA<6>
  VDD(21)  = PVDDQ_GHJ
  A3  = M_J_MA<3>
  A1  = M_J_MA<1>
  VDD(20)  = PVDDQ_GHJ
  CK0P  = M_J_CLK_DP<0>
  CK0N  = M_J_CLK_DN<0>
  VDD(19)  = PVDDQ_GHJ
  VTT(1)  = PVTT_GHJ
  EVENT_N  = FM_DIMM_EVENT_COD_N
  A0  = M_J_MA<0>
  VDD(18)  = PVDDQ_GHJ
  BA(0)  = M_J_BA<0>
  A16_RAS_N  = M_J_MA<16>
  VDD(17)  = PVDDQ_GHJ
  S0_N  = M_J_CS_N<0>
  VDD(16)  = PVDDQ_GHJ
  A15_CAS_N  = M_J_MA<15>
  ODT(0)  = M_J_ODT<0>
  VDD(15)  = PVDDQ_GHJ
  S1_N  = M_J_CS_N<1>
  VDD(14)  = PVDDQ_GHJ
  ODT(1)  = M_J_ODT<1>
  VDD(13)  = PVDDQ_GHJ
  S2_N_C(0)  = M_J_CS_N<2>
  VSS(67)  = GND
  DQ(36)  = M_J_DQ<37>
  VSS(66)  = GND
  DQ(32)  = M_J_DQ<33>
  VSS(65)  = GND
  DQS13P  = M_J_DQS_DP<13>
  DQS13N  = M_J_DQS_DN<13>
  VSS(64)  = GND
  DQ(38)  = M_J_DQ<39>
  VSS(63)  = GND
  DQ(34)  = M_J_DQ<35>
  VSS(62)  = GND
  DQ(44)  = M_J_DQ<45>
  VSS(61)  = GND
  DQ(40)  = M_J_DQ<41>
  VSS(60)  = GND
  DQS14P  = M_J_DQS_DP<14>
  DQS14N  = M_J_DQS_DN<14>
  VSS(59)  = GND
  DQ(46)  = M_J_DQ<47>
  VSS(58)  = GND
  DQ(42)  = M_J_DQ<43>
  VSS(57)  = GND
  DQ(52)  = M_J_DQ<53>
  VSS(56)  = GND
  DQ(48)  = M_J_DQ<49>
  VSS(55)  = GND
  DQS15P  = M_J_DQS_DP<15>
  DQS15N  = M_J_DQS_DN<15>
  VSS(54)  = GND
  DQ(54)  = M_J_DQ<55>
  VSS(53)  = GND
  DQ(50)  = M_J_DQ<51>
  VSS(52)  = GND
  DQ(60)  = M_J_DQ<61>
  VSS(51)  = GND
  DQ(56)  = M_J_DQ<57>
  VSS(50)  = GND
  DQS16P  = M_J_DQS_DP<16>
  DQS16N  = M_J_DQS_DN<16>
  VSS(49)  = GND
  DQ(62)  = M_J_DQ<63>
  VSS(48)  = GND
  DQ(58)  = M_J_DQ<59>
  VSS(47)  = GND
  SA(0)  = GND
  SA(1)  = GND
  SCL  = SMB_DDR_GHJ_VPP_SCL
  VPP(4)  = PVPP_GHJ
  VPP(3)  = PVPP_GHJ
  RFU(2)  = TP_CH_J_DIMM_J0_RFU_2
  \12v\(0)  = P12V_NVDIMM_GHJ
  VREFCA  = M_J_VREF
  VSS(46)  = GND
  DQ(5)  = M_J_DQ<4>
  VSS(45)  = GND
  DQ(1)  = M_J_DQ<0>
  VSS(44)  = GND
  DQS0N  = M_J_DQS_DN<0>
  DQS0P  = M_J_DQS_DP<0>
  VSS(43)  = GND
  DQ(7)  = M_J_DQ<6>
  VSS(42)  = GND
  DQ(3)  = M_J_DQ<2>
  VSS(41)  = GND
  DQ(13)  = M_J_DQ<12>
  VSS(40)  = GND
  DQ(9)  = M_J_DQ<8>
  VSS(39)  = GND
  DQS1N  = M_J_DQS_DN<1>
  DQS1P  = M_J_DQS_DP<1>
  VSS(38)  = GND
  DQ(15)  = M_J_DQ<14>
  VSS(37)  = GND
  DQ(11)  = M_J_DQ<10>
  VSS(36)  = GND
  DQ(21)  = M_J_DQ<20>
  VSS(35)  = GND
  DQ(17)  = M_J_DQ<16>
  VSS(34)  = GND
  DQS2N  = M_J_DQS_DN<2>
  DQS2P  = M_J_DQS_DP<2>
  VSS(33)  = GND
  DQ(23)  = M_J_DQ<22>
  VSS(32)  = GND
  DQ(19)  = M_J_DQ<18>
  VSS(31)  = GND
  DQ(29)  = M_J_DQ<28>
  VSS(30)  = GND
  DQ(25)  = M_J_DQ<24>
  VSS(29)  = GND
  DQS3N  = M_J_DQS_DN<3>
  DQS3P  = M_J_DQS_DP<3>
  VSS(28)  = GND
  DQ(31)  = M_J_DQ<30>
  VSS(27)  = GND
  DQ(27)  = M_J_DQ<26>
  VSS(26)  = GND
  CB(5)  = M_J_ECC<4>
  VSS(25)  = GND
  CB(1)  = M_J_ECC<0>
  VSS(24)  = GND
  DQS8N  = M_J_DQS_DN<8>
  DQS8P  = M_J_DQS_DP<8>
  VSS(23)  = GND
  CB(7)  = M_J_ECC<6>
  VSS(22)  = GND
  CB(3)  = M_J_ECC<2>
  VSS(21)  = GND
  CKE(1)  = M_J_CKE<1>
  VDD(12)  = PVDDQ_GHJ
  RFU(0)  = TP_CH_J_DIMM_J0_RFU_0
  VDD(11)  = PVDDQ_GHJ
  BG(1)  = M_J_BG<1>
  ALERT_N  = M_J_ALERT_N
  VDD(10)  = PVDDQ_GHJ
  A11  = M_J_MA<11>
  A7  = M_J_MA<7>
  VDD(9)  = PVDDQ_GHJ
  A5  = M_J_MA<5>
  A4  = M_J_MA<4>
  VDD(8)  = PVDDQ_GHJ
  A2  = M_J_MA<2>
  VDD(7)  = PVDDQ_GHJ
  CK1P  = M_J_CLK_DP<1>
  CK1N  = M_J_CLK_DN<1>
  VDD(6)  = PVDDQ_GHJ
  VTT(0)  = PVTT_GHJ
  PAR  = M_J_PAR
  VDD(5)  = PVDDQ_GHJ
  BA(1)  = M_J_BA<1>
  A10  = M_J_MA<10>
  VDD(4)  = PVDDQ_GHJ
  RFU(1)  = TP_CH_J_DIMM_J0_RFU_1
  A14_WE_N  = M_J_MA<14>
  VDD(3)  = PVDDQ_GHJ
  SAVE_N_NC  = FM_ADR_COMPLETE_GHJ_N
  VDD(2)  = PVDDQ_GHJ
  A13  = M_J_MA<13>
  VDD(1)  = PVDDQ_GHJ
  A17  = M_J_MA<17>
  C(2)  = M_J_C<2>
  VDD(0)  = PVDDQ_GHJ
  S3_N_C(1)  = M_J_CS_N<3>
  SA(2)  = PVPP_GHJ
  VSS(20)  = GND
  DQ(37)  = M_J_DQ<36>
  VSS(19)  = GND
  DQ(33)  = M_J_DQ<32>
  VSS(18)  = GND
  DQS4N  = M_J_DQS_DN<4>
  DQS4P  = M_J_DQS_DP<4>
  VSS(17)  = GND
  DQ(39)  = M_J_DQ<38>
  VSS(16)  = GND
  DQ(35)  = M_J_DQ<34>
  VSS(15)  = GND
  DQ(45)  = M_J_DQ<44>
  VSS(14)  = GND
  DQ(41)  = M_J_DQ<40>
  VSS(13)  = GND
  DQS5N  = M_J_DQS_DN<5>
  DQS5P  = M_J_DQS_DP<5>
  VSS(12)  = GND
  DQ(47)  = M_J_DQ<46>
  VSS(11)  = GND
  DQ(43)  = M_J_DQ<42>
  VSS(10)  = GND
  DQ(53)  = M_J_DQ<52>
  VSS(9)  = GND
  DQ(49)  = M_J_DQ<48>
  VSS(8)  = GND
  DQS6N  = M_J_DQS_DN<6>
  DQS6P  = M_J_DQS_DP<6>
  VSS(7)  = GND
  DQ(55)  = M_J_DQ<54>
  VSS(6)  = GND
  DQ(51)  = M_J_DQ<50>
  VSS(5)  = GND
  DQ(61)  = M_J_DQ<60>
  VSS(4)  = GND
  DQ(57)  = M_J_DQ<56>
  VSS(3)  = GND
  DQS7N  = M_J_DQS_DN<7>
  DQS7P  = M_J_DQS_DP<7>
  VSS(2)  = GND
  DQ(63)  = M_J_DQ<62>
  VSS(1)  = GND
  DQ(59)  = M_J_DQ<58>
  VSS(0)  = GND
  VDDSPD  = PVPP_GHJ
  SDA  = SMB_DDR_GHJ_VPP_SDA
  VPP(1)  = PVPP_GHJ
  VPP(0)  = PVPP_GHJ
  VPP(2)  = PVPP_GHJ

(kicad_pcb
	(version 20260206)
	(generator "pcbnew")
	(generator_version "10.0")
	(general
		(thickness 1.6)
		(legacy_teardrops no)
	)
	(paper "A4")
	(title_block
		(title "Wiwynn_Tioga_Pass_MB.brd")
		(comment 1 "Tioga Pass / footprint 437 of 4770 (J1G3), pads 1-51 of 291")
	)
	(layers
		(0 "F.Cu" signal "TOP")
		(4 "In1.Cu" signal "L2GND")
		(6 "In2.Cu" signal "L3")
		(8 "In3.Cu" signal "L4GND")
		(10 "In4.Cu" signal "L5")
		(12 "In5.Cu" signal "L6GND")
		(14 "In6.Cu" signal "L7VCC")
		(16 "In7.Cu" signal "L8VCC")
		(18 "In8.Cu" signal "L9GND")
		(20 "In9.Cu" signal "L10")
		(22 "In10.Cu" signal "L11GND")
		(24 "In11.Cu" signal "L12")
		(26 "In12.Cu" signal "L13GND")
		(2 "B.Cu" signal "BOTTOM")
		(9 "F.Adhes" user "F.Adhesive")
		(11 "B.Adhes" user "B.Adhesive")
		(13 "F.Paste" user "Package Geometry/Pastemask Top")
		(15 "B.Paste" user "Package Geometry/Pastemask Bottom")
		(5 "F.SilkS" user "Ref Des/Silkscreen Top")
		(7 "B.SilkS" user "Ref Des/Silkscreen Bottom")
		(1 "F.Mask" user "Board Geometry/Soldermask Top")
		(3 "B.Mask" user "Board Geometry/Soldermask Bottom")
		(17 "Dwgs.User" user "User.Drawings")
		(19 "Cmts.User" user "User.Comments")
		(21 "Eco1.User" user "User.Eco1")
		(23 "Eco2.User" user "User.Eco2")
		(25 "Edge.Cuts" user "Board Geometry/Outline")
		(27 "Margin" user)
		(31 "F.CrtYd" user "Package Geometry/Place Bound Top")
		(29 "B.CrtYd" user "Package Geometry/Place Bound Bottom")
		(35 "F.Fab" user "Ref Des/Assembly Top")
		(33 "B.Fab" user "Ref Des/Assembly Bottom")
	)
	(footprint ""
		(layer "F.Cu")
		(at 29.699458 3.778758 90)
		(property "Reference" "J1G3"
			(at 7.054088 34.562542 0)
			(unlocked yes)
			(layer "F.SilkS")
			(effects
				(font
					(size 0.7874 0.5842)
					(thickness 0.1524)
				)
				(justify left)
			)
		)
		(property "Value" ""
			(at 0 0 90)
			(layer "F.Fab")
			(effects
				(font
					(size 1.27 1.27)
				)
			)
		)
		(duplicate_pad_numbers_are_jumpers no)
		(pad "" thru_hole circle
			(at 2.29997 -5.649976 90)
			(size 2.8194 2.8194)
			(drill 2.4384)
			(layers "*.Cu" "*.Mask")
			(remove_unused_layers no)
			(clearance 0.127)
			(thermal_gap 0.127)
		)
		(pad "" thru_hole oval
			(at 2.29997 68.90004 90)
			(size 2.8194 1.5748)
			(drill oval 2.4384 1.1938)
			(layers "*.Cu" "*.Mask")
			(remove_unused_layers no)
			(clearance 0.127)
			(thermal_gap 0.127)
		)
		(pad "" thru_hole circle
			(at 2.29997 132.299964 90)
			(size 2.8194 2.8194)
			(drill 2.4384)
			(layers "*.Cu" "*.Mask")
			(remove_unused_layers no)
			(clearance 0.127)
			(thermal_gap 0.127)
		)
		(pad "1" smd rect
			(at 0 0 90)
			(size 1.8034 0.508)
			(layers "F.Cu" "F.Mask" "F.Paste")
			(net "P12V_NVDIMM_GHJ")
		)
		(pad "2" smd rect
			(at 0 0.849884 90)
			(size 1.8034 0.508)
			(layers "F.Cu" "F.Mask" "F.Paste")
			(net "GND")
		)
		(pad "3" smd rect
			(at 0 1.700022 90)
			(size 1.8034 0.508)
			(layers "F.Cu" "F.Mask" "F.Paste")
			(net "M_J_DQ<5>")
		)
		(pad "4" smd rect
			(at 0 2.549906 90)
			(size 1.8034 0.508)
			(layers "F.Cu" "F.Mask" "F.Paste")
			(net "GND")
		)
		(pad "5" smd rect
			(at 0 3.400044 90)
			(size 1.8034 0.508)
			(layers "F.Cu" "F.Mask" "F.Paste")
			(net "M_J_DQ<1>")
		)
		(pad "6" smd rect
			(at 0 4.249928 90)
			(size 1.8034 0.508)
			(layers "F.Cu" "F.Mask" "F.Paste")
			(net "GND")
		)
		(pad "7" smd rect
			(at 0 5.100066 90)
			(size 1.8034 0.508)
			(layers "F.Cu" "F.Mask" "F.Paste")
			(net "M_J_DQS_DP<9>")
		)
		(pad "8" smd rect
			(at 0 5.94995 90)
			(size 1.8034 0.508)
			(layers "F.Cu" "F.Mask" "F.Paste")
			(net "M_J_DQS_DN<9>")
		)
		(pad "9" smd rect
			(at 0 6.800088 90)
			(size 1.8034 0.508)
			(layers "F.Cu" "F.Mask" "F.Paste")
			(net "GND")
		)
		(pad "10" smd rect
			(at 0 7.649972 90)
			(size 1.8034 0.508)
			(layers "F.Cu" "F.Mask" "F.Paste")
			(net "M_J_DQ<7>")
		)
		(pad "11" smd rect
			(at 0 8.50011 90)
			(size 1.8034 0.508)
			(layers "F.Cu" "F.Mask" "F.Paste")
			(net "GND")
		)
		(pad "12" smd rect
			(at 0 9.349994 90)
			(size 1.8034 0.508)
			(layers "F.Cu" "F.Mask" "F.Paste")
			(net "M_J_DQ<3>")
		)
		(pad "13" smd rect
			(at 0 10.199878 90)
			(size 1.8034 0.508)
			(layers "F.Cu" "F.Mask" "F.Paste")
			(net "GND")
		)
		(pad "14" smd rect
			(at 0 11.050016 90)
			(size 1.8034 0.508)
			(layers "F.Cu" "F.Mask" "F.Paste")
			(net "M_J_DQ<13>")
		)
		(pad "15" smd rect
			(at 0 11.8999 90)
			(size 1.8034 0.508)
			(layers "F.Cu" "F.Mask" "F.Paste")
			(net "GND")
		)
		(pad "16" smd rect
			(at 0 12.750038 90)
			(size 1.8034 0.508)
			(layers "F.Cu" "F.Mask" "F.Paste")
			(net "M_J_DQ<9>")
		)
		(pad "17" smd rect
			(at 0 13.599922 90)
			(size 1.8034 0.508)
			(layers "F.Cu" "F.Mask" "F.Paste")
			(net "GND")
		)
		(pad "18" smd rect
			(at 0 14.45006 90)
			(size 1.8034 0.508)
			(layers "F.Cu" "F.Mask" "F.Paste")
			(net "M_J_DQS_DP<10>")
		)
		(pad "19" smd rect
			(at 0 15.299944 90)
			(size 1.8034 0.508)
			(layers "F.Cu" "F.Mask" "F.Paste")
			(net "M_J_DQS_DN<10>")
		)
		(pad "20" smd rect
			(at 0 16.150082 90)
			(size 1.8034 0.508)
			(layers "F.Cu" "F.Mask" "F.Paste")
			(net "GND")
		)
		(pad "21" smd rect
			(at 0 16.999966 90)
			(size 1.8034 0.508)
			(layers "F.Cu" "F.Mask" "F.Paste")
			(net "M_J_DQ<15>")
		)
		(pad "22" smd rect
			(at 0 17.850104 90)
			(size 1.8034 0.508)
			(layers "F.Cu" "F.Mask" "F.Paste")
			(net "GND")
		)
		(pad "23" smd rect
			(at 0 18.699988 90)
			(size 1.8034 0.508)
			(layers "F.Cu" "F.Mask" "F.Paste")
			(net "M_J_DQ<11>")
		)
		(pad "24" smd rect
			(at 0 19.550126 90)
			(size 1.8034 0.508)
			(layers "F.Cu" "F.Mask" "F.Paste")
			(net "GND")
		)
		(pad "25" smd rect
			(at 0 20.40001 90)
			(size 1.8034 0.508)
			(layers "F.Cu" "F.Mask" "F.Paste")
			(net "M_J_DQ<21>")
		)
		(pad "26" smd rect
			(at 0 21.249894 90)
			(size 1.8034 0.508)
			(layers "F.Cu" "F.Mask" "F.Paste")
			(net "GND")
		)
		(pad "27" smd rect
			(at 0 22.100032 90)
			(size 1.8034 0.508)
			(layers "F.Cu" "F.Mask" "F.Paste")
			(net "M_J_DQ<17>")
		)
		(pad "28" smd rect
			(at 0 22.949916 90)
			(size 1.8034 0.508)
			(layers "F.Cu" "F.Mask" "F.Paste")
			(net "GND")
		)
		(pad "29" smd rect
			(at 0 23.800054 90)
			(size 1.8034 0.508)
			(layers "F.Cu" "F.Mask" "F.Paste")
			(net "M_J_DQS_DP<11>")
		)
		(pad "30" smd rect
			(at 0 24.649938 90)
			(size 1.8034 0.508)
			(layers "F.Cu" "F.Mask" "F.Paste")
			(net "M_J_DQS_DN<11>")
		)
		(pad "31" smd rect
			(at 0 25.500076 90)
			(size 1.8034 0.508)
			(layers "F.Cu" "F.Mask" "F.Paste")
			(net "GND")
		)
		(pad "32" smd rect
			(at 0 26.34996 90)
			(size 1.8034 0.508)
			(layers "F.Cu" "F.Mask" "F.Paste")
			(net "M_J_DQ<23>")
		)
		(pad "33" smd rect
			(at 0 27.200098 90)
			(size 1.8034 0.508)
			(layers "F.Cu" "F.Mask" "F.Paste")
			(net "GND")
		)
		(pad "34" smd rect
			(at 0 28.049982 90)
			(size 1.8034 0.508)
			(layers "F.Cu" "F.Mask" "F.Paste")
			(net "M_J_DQ<19>")
		)
		(pad "35" smd rect
			(at 0 28.90012 90)
			(size 1.8034 0.508)
			(layers "F.Cu" "F.Mask" "F.Paste")
			(net "GND")
		)
		(pad "36" smd rect
			(at 0 29.750004 90)
			(size 1.8034 0.508)
			(layers "F.Cu" "F.Mask" "F.Paste")
			(net "M_J_DQ<29>")
		)
		(pad "37" smd rect
			(at 0 30.599888 90)
			(size 1.8034 0.508)
			(layers "F.Cu" "F.Mask" "F.Paste")
			(net "GND")
		)
		(pad "38" smd rect
			(at 0 31.450026 90)
			(size 1.8034 0.508)
			(layers "F.Cu" "F.Mask" "F.Paste")
			(net "M_J_DQ<25>")
		)
		(pad "39" smd rect
			(at 0 32.29991 90)
			(size 1.8034 0.508)
			(layers "F.Cu" "F.Mask" "F.Paste")
			(net "GND")
		)
		(pad "40" smd rect
			(at 0 33.150048 90)
			(size 1.8034 0.508)
			(layers "F.Cu" "F.Mask" "F.Paste")
			(net "M_J_DQS_DP<12>")
		)
		(pad "41" smd rect
			(at 0 33.999932 90)
			(size 1.8034 0.508)
			(layers "F.Cu" "F.Mask" "F.Paste")
			(net "M_J_DQS_DN<12>")
		)
		(pad "42" smd rect
			(at 0 34.85007 90)
			(size 1.8034 0.508)
			(layers "F.Cu" "F.Mask" "F.Paste")
			(net "GND")
		)
		(pad "43" smd rect
			(at 0 35.699954 90)
			(size 1.8034 0.508)
			(layers "F.Cu" "F.Mask" "F.Paste")
			(net "M_J_DQ<31>")
		)
		(pad "44" smd rect
			(at 0 36.550092 90)
			(size 1.8034 0.508)
			(layers "F.Cu" "F.Mask" "F.Paste")
			(net "GND")
		)
		(pad "45" smd rect
			(at 0 37.399976 90)
			(size 1.8034 0.508)
			(layers "F.Cu" "F.Mask" "F.Paste")
			(net "M_J_DQ<27>")
		)
		(pad "46" smd rect
			(at 0 38.250114 90)
			(size 1.8034 0.508)
			(layers "F.Cu" "F.Mask" "F.Paste")
			(net "GND")
		)
		(pad "47" smd rect
			(at 0 39.099998 90)
			(size 1.8034 0.508)
			(layers "F.Cu" "F.Mask" "F.Paste")
			(net "M_J_ECC<5>")
		)
		(pad "48" smd rect
			(at 0 39.949882 90)
			(size 1.8034 0.508)
			(layers "F.Cu" "F.Mask" "F.Paste")
			(net "GND")
		)
	)
)
